# Stackup_grand teton_MB_18L_2p413mm_EM-890K_VL411_Rev0p6_20230202.xls — Manufacuring violation (pcb-stackup)
| Description | Quanta layout design rule | The stackup design rule |  |
| Min. Innerlayer Line Width, 0.5 oz copper (mil) | 3 | NA | Normal |
| Min. Innerlayer Space, 0.5 oz copper (mil) | 3.5 | NA | Medium |
| Min. Innerlayer Line Width,   1 oz copper (mil) | 4 | 3 | High |
| Min. Innerlayer Space, 1 oz copper (mil) | 4 | 3 |  |
| Min. Innerlayer Line Width,   2oz copper (mil) | 6 | NA |  |
| Min. Innerlayer Space,  2oz copper (mil) | 6 | NA |  |
| Min. Outerlayer line width, 0.5oz copper foil (mil) | 3.5 | 3 |  |
| Min. Outerlayer Space, 0.5oz copper foil (mil) | 3.5 | 4.5 |  |
| Min. Inner Core/PP thickness (mil) | 3 | 3.5 |  |
| Max. Aspect Ratio for min. DHS | 12.24 | 9.69 |  |
